(kicad_pcb
	(version 20260206)
	(generator "pcbnew")
	(generator_version "10.0")
	(general
		(thickness 1.6)
		(legacy_teardrops no)
	)
	(paper "A4")
	(title_block
		(title "04192023_DAF0TMB3IC0_F0TG_MB_C_brd_V02_OCP.brd")
		(comment 1 "Grand Teton / footprints 2392-2400 of 8354")
	)
	(layers
		(0 "F.Cu" signal "TOP")
		(4 "In1.Cu" signal "GND")
		(6 "In2.Cu" signal "IN1")
		(8 "In3.Cu" signal "GND1")
		(10 "In4.Cu" signal "IN2")
		(12 "In5.Cu" signal "GND2")
		(14 "In6.Cu" signal "IN3")
		(16 "In7.Cu" signal "GND3")
		(18 "In8.Cu" signal "VCC")
		(20 "In9.Cu" signal "VCC1")
		(22 "In10.Cu" signal "GND4")
		(24 "In11.Cu" signal "IN4")
		(26 "In12.Cu" signal "GND5")
		(28 "In13.Cu" signal "IN5")
		(30 "In14.Cu" signal "GND6")
		(32 "In15.Cu" signal "IN6")
		(34 "In16.Cu" signal "GND7")
		(2 "B.Cu" signal "BOTTOM")
		(9 "F.Adhes" user "F.Adhesive")
		(11 "B.Adhes" user "B.Adhesive")
		(13 "F.Paste" user "Package Geometry/Pastemask Top")
		(15 "B.Paste" user "Package Geometry/Pastemask Bottom")
		(5 "F.SilkS" user "Ref Des/Silkscreen Top")
		(7 "B.SilkS" user "Ref Des/Silkscreen Bottom")
		(1 "F.Mask" user "Board Geometry/Soldermask Top")
		(3 "B.Mask" user "Board Geometry/Soldermask Bottom")
		(17 "Dwgs.User" user "User.Drawings")
		(19 "Cmts.User" user "User.Comments")
		(21 "Eco1.User" user "User.Eco1")
		(23 "Eco2.User" user "User.Eco2")
		(25 "Edge.Cuts" user "Board Geometry/Outline")
		(27 "Margin" user)
		(31 "F.CrtYd" user "Package Geometry/Place Bound Top")
		(29 "B.CrtYd" user "Package Geometry/Place Bound Bottom")
		(35 "F.Fab" user "Ref Des/Assembly Top")
		(33 "B.Fab" user "Ref Des/Assembly Bottom")
	)
	(footprint ""
		(layer "F.Cu")
		(at 432.2572 -17.624298 90)
		(property "Reference" "C1578"
			(at 0 0 90)
			(layer "F.SilkS")
			(hide yes)
			(effects
				(font
					(size 1.27 1.27)
				)
			)
		)
		(property "Value" ""
			(at 0 0 90)
			(layer "F.Fab")
			(effects
				(font
					(size 1.27 1.27)
				)
			)
		)
		(duplicate_pad_numbers_are_jumpers no)
		(fp_line
			(start 0.299974 -0.150114)
			(end 0.299974 0.150114)
			(stroke
				(width 0.1)
				(type default)
			)
			(layer "F.Fab")
		)
		(fp_line
			(start -0.299974 -0.150114)
			(end 0.299974 -0.150114)
			(stroke
				(width 0.1)
				(type default)
			)
			(layer "F.Fab")
		)
		(fp_line
			(start 0.299974 0.150114)
			(end -0.299974 0.150114)
			(stroke
				(width 0.1)
				(type default)
			)
			(layer "F.Fab")
		)
		(fp_line
			(start -0.299974 0.150114)
			(end -0.299974 -0.150114)
			(stroke
				(width 0.1)
				(type default)
			)
			(layer "F.Fab")
		)
		(pad "1" smd rect
			(at -0.2667 0 90)
			(size 0.3048 0.381)
			(layers "F.Cu" "F.Mask" "F.Paste")
			(net "P5E_CPU0_G3_TX_C_DN<0>")
		)
		(pad "2" smd rect
			(at 0.2667 0 90)
			(size 0.3048 0.381)
			(layers "F.Cu" "F.Mask" "F.Paste")
			(net "P5E_CPU0_G3_TX_DN<0>")
		)
	)
	(footprint ""
		(layer "F.Cu")
		(at 417.33724 -383.88163 -90)
		(property "Reference" "C849"
			(at 0 0 270)
			(layer "F.SilkS")
			(hide yes)
			(effects
				(font
					(size 1.27 1.27)
				)
			)
		)
		(property "Value" ""
			(at 0 0 270)
			(layer "F.Fab")
			(effects
				(font
					(size 1.27 1.27)
				)
			)
		)
		(duplicate_pad_numbers_are_jumpers no)
		(fp_line
			(start -0.299974 0.150114)
			(end -0.299974 -0.150114)
			(stroke
				(width 0.1)
				(type default)
			)
			(layer "F.Fab")
		)
		(fp_line
			(start 0.299974 0.150114)
			(end -0.299974 0.150114)
			(stroke
				(width 0.1)
				(type default)
			)
			(layer "F.Fab")
		)
		(fp_line
			(start -0.299974 -0.150114)
			(end 0.299974 -0.150114)
			(stroke
				(width 0.1)
				(type default)
			)
			(layer "F.Fab")
		)
		(fp_line
			(start 0.299974 -0.150114)
			(end 0.299974 0.150114)
			(stroke
				(width 0.1)
				(type default)
			)
			(layer "F.Fab")
		)
		(pad "1" smd rect
			(at -0.2667 0 270)
			(size 0.3048 0.381)
			(layers "F.Cu" "F.Mask" "F.Paste")
			(net "P5E_CPU0_P2_TX_C_DP<10>")
		)
		(pad "2" smd rect
			(at 0.2667 0 270)
			(size 0.3048 0.381)
			(layers "F.Cu" "F.Mask" "F.Paste")
			(net "P5E_CPU0_P2_TX_DP<10>")
		)
	)
	(footprint ""
		(layer "F.Cu")
		(at 8.406384 -381.562356)
		(property "Reference" "PR6602"
			(at 0 0 0)
			(layer "F.SilkS")
			(hide yes)
			(effects
				(font
					(size 1.27 1.27)
				)
			)
		)
		(property "Value" ""
			(at 0 0 0)
			(layer "F.Fab")
			(effects
				(font
					(size 1.27 1.27)
				)
			)
		)
		(duplicate_pad_numbers_are_jumpers no)
		(fp_line
			(start -0.7874 -0.4064)
			(end 0.7874 -0.4064)
			(stroke
				(width 0.1524)
				(type default)
			)
			(layer "F.SilkS")
		)
		(fp_line
			(start -0.7874 0.4064)
			(end -0.7874 -0.4064)
			(stroke
				(width 0.1524)
				(type default)
			)
			(layer "F.SilkS")
		)
		(fp_line
			(start 0.7874 -0.4064)
			(end 0.7874 0.4064)
			(stroke
				(width 0.1524)
				(type default)
			)
			(layer "F.SilkS")
		)
		(fp_line
			(start 0.7874 0.4064)
			(end -0.7874 0.4064)
			(stroke
				(width 0.1524)
				(type default)
			)
			(layer "F.SilkS")
		)
		(fp_line
			(start -0.67945 -0.305054)
			(end -0.12065 -0.305054)
			(stroke
				(width 0.1)
				(type default)
			)
			(layer "F.Fab")
		)
		(fp_line
			(start -0.67945 0.3048)
			(end -0.67945 -0.305054)
			(stroke
				(width 0.1)
				(type default)
			)
			(layer "F.Fab")
		)
		(fp_line
			(start -0.12065 -0.305054)
			(end -0.12065 -0.2794)
			(stroke
				(width 0.1)
				(type default)
			)
			(layer "F.Fab")
		)
		(fp_line
			(start -0.12065 -0.2794)
			(end 0.12065 -0.2794)
			(stroke
				(width 0.1)
				(type default)
			)
			(layer "F.Fab")
		)
		(fp_line
			(start -0.12065 0.2794)
			(end -0.12065 0.3048)
			(stroke
				(width 0.1)
				(type default)
			)
			(layer "F.Fab")
		)
		(fp_line
			(start -0.12065 0.3048)
			(end -0.67945 0.3048)
			(stroke
				(width 0.1)
				(type default)
			)
			(layer "F.Fab")
		)
		(fp_line
			(start 0.120396 0.2794)
			(end -0.12065 0.2794)
			(stroke
				(width 0.1)
				(type default)
			)
			(layer "F.Fab")
		)
		(fp_line
			(start 0.120396 0.3048)
			(end 0.120396 0.2794)
			(stroke
				(width 0.1)
				(type default)
			)
			(layer "F.Fab")
		)
		(fp_line
			(start 0.12065 -0.3048)
			(end 0.67945 -0.3048)
			(stroke
				(width 0.1)
				(type default)
			)
			(layer "F.Fab")
		)
		(fp_line
			(start 0.12065 -0.2794)
			(end 0.12065 -0.3048)
			(stroke
				(width 0.1)
				(type default)
			)
			(layer "F.Fab")
		)
		(fp_line
			(start 0.67945 -0.3048)
			(end 0.67945 0.3048)
			(stroke
				(width 0.1)
				(type default)
			)
			(layer "F.Fab")
		)
		(fp_line
			(start 0.67945 0.3048)
			(end 0.120396 0.3048)
			(stroke
				(width 0.1)
				(type default)
			)
			(layer "F.Fab")
		)
		(pad "1" smd circle
			(at -0.40005 0)
			(size 0 0)
			(layers "F.Cu" "F.Mask" "F.Paste")
			(net "P0V9_RETIMER_CPU1_SENSE_SH_N")
		)
		(pad "2" smd circle
			(at 0.40005 0)
			(size 0 0)
			(layers "F.Cu" "F.Mask" "F.Paste")
			(net "GND")
		)
	)
	(footprint ""
		(layer "F.Cu")
		(at 386.211826 -63.3095 180)
		(property "Reference" "R1629"
			(at 0 0 180)
			(layer "F.SilkS")
			(hide yes)
			(effects
				(font
					(size 1.27 1.27)
				)
			)
		)
		(property "Value" ""
			(at 0 0 180)
			(layer "F.Fab")
			(effects
				(font
					(size 1.27 1.27)
				)
			)
		)
		(duplicate_pad_numbers_are_jumpers no)
		(fp_line
			(start 0.7874 0.4064)
			(end -0.7874 0.4064)
			(stroke
				(width 0.1524)
				(type default)
			)
			(layer "F.SilkS")
		)
		(fp_line
			(start 0.7874 -0.4064)
			(end 0.7874 0.4064)
			(stroke
				(width 0.1524)
				(type default)
			)
			(layer "F.SilkS")
		)
		(fp_line
			(start -0.7874 0.4064)
			(end -0.7874 -0.4064)
			(stroke
				(width 0.1524)
				(type default)
			)
			(layer "F.SilkS")
		)
		(fp_line
			(start -0.7874 -0.4064)
			(end 0.7874 -0.4064)
			(stroke
				(width 0.1524)
				(type default)
			)
			(layer "F.SilkS")
		)
		(fp_line
			(start 0.67945 0.3048)
			(end 0.120396 0.3048)
			(stroke
				(width 0.1)
				(type default)
			)
			(layer "F.Fab")
		)
		(fp_line
			(start 0.67945 -0.3048)
			(end 0.67945 0.3048)
			(stroke
				(width 0.1)
				(type default)
			)
			(layer "F.Fab")
		)
		(fp_line
			(start 0.12065 -0.2794)
			(end 0.12065 -0.3048)
			(stroke
				(width 0.1)
				(type default)
			)
			(layer "F.Fab")
		)
		(fp_line
			(start 0.12065 -0.3048)
			(end 0.67945 -0.3048)
			(stroke
				(width 0.1)
				(type default)
			)
			(layer "F.Fab")
		)
		(fp_line
			(start 0.120396 0.3048)
			(end 0.120396 0.2794)
			(stroke
				(width 0.1)
				(type default)
			)
			(layer "F.Fab")
		)
		(fp_line
			(start 0.120396 0.2794)
			(end -0.12065 0.2794)
			(stroke
				(width 0.1)
				(type default)
			)
			(layer "F.Fab")
		)
		(fp_line
			(start -0.12065 0.3048)
			(end -0.67945 0.3048)
			(stroke
				(width 0.1)
				(type default)
			)
			(layer "F.Fab")
		)
		(fp_line
			(start -0.12065 0.2794)
			(end -0.12065 0.3048)
			(stroke
				(width 0.1)
				(type default)
			)
			(layer "F.Fab")
		)
		(fp_line
			(start -0.12065 -0.2794)
			(end 0.12065 -0.2794)
			(stroke
				(width 0.1)
				(type default)
			)
			(layer "F.Fab")
		)
		(fp_line
			(start -0.12065 -0.305054)
			(end -0.12065 -0.2794)
			(stroke
				(width 0.1)
				(type default)
			)
			(layer "F.Fab")
		)
		(fp_line
			(start -0.67945 0.3048)
			(end -0.67945 -0.305054)
			(stroke
				(width 0.1)
				(type default)
			)
			(layer "F.Fab")
		)
		(fp_line
			(start -0.67945 -0.305054)
			(end -0.12065 -0.305054)
			(stroke
				(width 0.1)
				(type default)
			)
			(layer "F.Fab")
		)
		(pad "1" smd circle
			(at -0.40005 0 180)
			(size 0 0)
			(layers "F.Cu" "F.Mask" "F.Paste")
			(net "HDT_CPU0_HDT_CONN_TESTEN")
		)
		(pad "2" smd circle
			(at 0.40005 0 180)
			(size 0 0)
			(layers "F.Cu" "F.Mask" "F.Paste")
			(net "GND")
		)
	)
	(footprint ""
		(layer "F.Cu")
		(at 103.998522 -33.185354 90)
		(property "Reference" "R343"
			(at 0 0 90)
			(layer "F.SilkS")
			(hide yes)
			(effects
				(font
					(size 1.27 1.27)
				)
			)
		)
		(property "Value" ""
			(at 0 0 90)
			(layer "F.Fab")
			(effects
				(font
					(size 1.27 1.27)
				)
			)
		)
		(duplicate_pad_numbers_are_jumpers no)
		(fp_line
			(start 0.32512 -0.175006)
			(end 0.32512 0.175006)
			(stroke
				(width 0.1)
				(type default)
			)
			(layer "F.Fab")
		)
		(fp_line
			(start -0.32512 -0.175006)
			(end 0.32512 -0.175006)
			(stroke
				(width 0.1)
				(type default)
			)
			(layer "F.Fab")
		)
		(fp_line
			(start 0.32512 0.175006)
			(end -0.32512 0.175006)
			(stroke
				(width 0.1)
				(type default)
			)
			(layer "F.Fab")
		)
		(fp_line
			(start -0.32512 0.175006)
			(end -0.32512 -0.175006)
			(stroke
				(width 0.1)
				(type default)
			)
			(layer "F.Fab")
		)
		(pad "1" smd rect
			(at -0.2667 0 90)
			(size 0.3048 0.381)
			(layers "F.Cu" "F.Mask" "F.Paste")
			(net "USB2_CPU0_P0_R2_DP")
		)
		(pad "2" smd rect
			(at 0.2667 0 270)
			(size 0.3048 0.381)
			(layers "F.Cu" "F.Mask" "F.Paste")
			(net "GND")
		)
	)
	(footprint ""
		(layer "F.Cu")
		(at 130.511296 -373.03583 -90)
		(property "Reference" "C1525"
			(at 0 0 270)
			(layer "F.SilkS")
			(hide yes)
			(effects
				(font
					(size 1.27 1.27)
				)
			)
		)
		(property "Value" ""
			(at 0 0 270)
			(layer "F.Fab")
			(effects
				(font
					(size 1.27 1.27)
				)
			)
		)
		(duplicate_pad_numbers_are_jumpers no)
		(fp_line
			(start -0.299974 0.150114)
			(end -0.299974 -0.150114)
			(stroke
				(width 0.1)
				(type default)
			)
			(layer "F.Fab")
		)
		(fp_line
			(start 0.299974 0.150114)
			(end -0.299974 0.150114)
			(stroke
				(width 0.1)
				(type default)
			)
			(layer "F.Fab")
		)
		(fp_line
			(start -0.299974 -0.150114)
			(end 0.299974 -0.150114)
			(stroke
				(width 0.1)
				(type default)
			)
			(layer "F.Fab")
		)
		(fp_line
			(start 0.299974 -0.150114)
			(end 0.299974 0.150114)
			(stroke
				(width 0.1)
				(type default)
			)
			(layer "F.Fab")
		)
		(pad "1" smd rect
			(at -0.2667 0 270)
			(size 0.3048 0.381)
			(layers "F.Cu" "F.Mask" "F.Paste")
			(net "P5E_CPU1_P3_TX_C_DP<11>")
		)
		(pad "2" smd rect
			(at 0.2667 0 270)
			(size 0.3048 0.381)
			(layers "F.Cu" "F.Mask" "F.Paste")
			(net "P5E_CPU1_P3_TX_DP<11>")
		)
	)
	(footprint ""
		(layer "F.Cu")
		(at 49.860454 -349.386398 90)
		(property "Reference" "PC433"
			(at 0 0 90)
			(layer "F.SilkS")
			(hide yes)
			(effects
				(font
					(size 1.27 1.27)
				)
			)
		)
		(property "Value" ""
			(at 0 0 90)
			(layer "F.Fab")
			(effects
				(font
					(size 1.27 1.27)
				)
			)
		)
		(duplicate_pad_numbers_are_jumpers no)
		(fp_line
			(start 0.7874 -0.4064)
			(end 0.7874 0.4064)
			(stroke
				(width 0.1524)
				(type default)
			)
			(layer "F.SilkS")
		)
		(fp_line
			(start -0.7874 -0.4064)
			(end 0.7874 -0.4064)
			(stroke
				(width 0.1524)
				(type default)
			)
			(layer "F.SilkS")
		)
		(fp_line
			(start 0.7874 0.4064)
			(end 0.447802 0.4064)
			(stroke
				(width 0.1524)
				(type default)
			)
			(layer "F.SilkS")
		)
		(fp_line
			(start -0.263398 0.4064)
			(end -0.7874 0.4064)
			(stroke
				(width 0.1524)
				(type default)
			)
			(layer "F.SilkS")
		)
		(fp_line
			(start -0.7874 0.4064)
			(end -0.7874 -0.4064)
			(stroke
				(width 0.1524)
				(type default)
			)
			(layer "F.SilkS")
		)
		(fp_line
			(start -0.12065 -0.305054)
			(end -0.12065 -0.2794)
			(stroke
				(width 0.1)
				(type default)
			)
			(layer "F.Fab")
		)
		(fp_line
			(start -0.67945 -0.305054)
			(end -0.12065 -0.305054)
			(stroke
				(width 0.1)
				(type default)
			)
			(layer "F.Fab")
		)
		(fp_line
			(start 0.67945 -0.3048)
			(end 0.67945 0.3048)
			(stroke
				(width 0.1)
				(type default)
			)
			(layer "F.Fab")
		)
		(fp_line
			(start 0.12065 -0.3048)
			(end 0.67945 -0.3048)
			(stroke
				(width 0.1)
				(type default)
			)
			(layer "F.Fab")
		)
		(fp_line
			(start 0.12065 -0.2794)
			(end 0.12065 -0.3048)
			(stroke
				(width 0.1)
				(type default)
			)
			(layer "F.Fab")
		)
		(fp_line
			(start -0.12065 -0.2794)
			(end 0.12065 -0.2794)
			(stroke
				(width 0.1)
				(type default)
			)
			(layer "F.Fab")
		)
		(fp_line
			(start 0.120396 0.2794)
			(end -0.12065 0.2794)
			(stroke
				(width 0.1)
				(type default)
			)
			(layer "F.Fab")
		)
		(fp_line
			(start -0.12065 0.2794)
			(end -0.12065 0.3048)
			(stroke
				(width 0.1)
				(type default)
			)
			(layer "F.Fab")
		)
		(fp_line
			(start 0.67945 0.3048)
			(end 0.120396 0.3048)
			(stroke
				(width 0.1)
				(type default)
			)
			(layer "F.Fab")
		)
		(fp_line
			(start 0.120396 0.3048)
			(end 0.120396 0.2794)
			(stroke
				(width 0.1)
				(type default)
			)
			(layer "F.Fab")
		)
		(fp_line
			(start -0.12065 0.3048)
			(end -0.67945 0.3048)
			(stroke
				(width 0.1)
				(type default)
			)
			(layer "F.Fab")
		)
		(fp_line
			(start -0.67945 0.3048)
			(end -0.67945 -0.305054)
			(stroke
				(width 0.1)
				(type default)
			)
			(layer "F.Fab")
		)
		(pad "1" smd circle
			(at -0.40005 0 90)
			(size 0 0)
			(layers "F.Cu" "F.Mask" "F.Paste")
			(net "PVDDIO_P1_VCC1")
		)
		(pad "2" smd circle
			(at 0.40005 0 90)
			(size 0 0)
			(layers "F.Cu" "F.Mask" "F.Paste")
			(net "GND")
		)
	)
	(footprint ""
		(layer "F.Cu")
		(at 145.233644 -370.57203 -90)
		(property "Reference" "C766"
			(at 0 0 270)
			(layer "F.SilkS")
			(hide yes)
			(effects
				(font
					(size 1.27 1.27)
				)
			)
		)
		(property "Value" ""
			(at 0 0 270)
			(layer "F.Fab")
			(effects
				(font
					(size 1.27 1.27)
				)
			)
		)
		(duplicate_pad_numbers_are_jumpers no)
		(fp_line
			(start -0.299974 0.150114)
			(end -0.299974 -0.150114)
			(stroke
				(width 0.1)
				(type default)
			)
			(layer "F.Fab")
		)
		(fp_line
			(start 0.299974 0.150114)
			(end -0.299974 0.150114)
			(stroke
				(width 0.1)
				(type default)
			)
			(layer "F.Fab")
		)
		(fp_line
			(start -0.299974 -0.150114)
			(end 0.299974 -0.150114)
			(stroke
				(width 0.1)
				(type default)
			)
			(layer "F.Fab")
		)
		(fp_line
			(start 0.299974 -0.150114)
			(end 0.299974 0.150114)
			(stroke
				(width 0.1)
				(type default)
			)
			(layer "F.Fab")
		)
		(pad "1" smd rect
			(at -0.2667 0 270)
			(size 0.3048 0.381)
			(layers "F.Cu" "F.Mask" "F.Paste")
			(net "P5E_CPU1_P2_TX_C_DN<3>")
		)
		(pad "2" smd rect
			(at 0.2667 0 270)
			(size 0.3048 0.381)
			(layers "F.Cu" "F.Mask" "F.Paste")
			(net "P5E_CPU1_P2_TX_DN<3>")
		)
	)
	(footprint ""
		(layer "F.Cu")
		(at 29.045662 -424.259502)
		(property "Reference" "R3277"
			(at 0 0 0)
			(layer "F.SilkS")
			(hide yes)
			(effects
				(font
					(size 1.27 1.27)
				)
			)
		)
		(property "Value" ""
			(at 0 0 0)
			(layer "F.Fab")
			(effects
				(font
					(size 1.27 1.27)
				)
			)
		)
		(duplicate_pad_numbers_are_jumpers no)
		(fp_line
			(start -0.7874 -0.4064)
			(end 0.7874 -0.4064)
			(stroke
				(width 0.1524)
				(type default)
			)
			(layer "F.SilkS")
		)
		(fp_line
			(start -0.7874 0.4064)
			(end -0.7874 -0.4064)
			(stroke
				(width 0.1524)
				(type default)
			)
			(layer "F.SilkS")
		)
		(fp_line
			(start 0.7874 -0.4064)
			(end 0.7874 0.4064)
			(stroke
				(width 0.1524)
				(type default)
			)
			(layer "F.SilkS")
		)
		(fp_line
			(start 0.7874 0.4064)
			(end -0.7874 0.4064)
			(stroke
				(width 0.1524)
				(type default)
			)
			(layer "F.SilkS")
		)
		(fp_line
			(start -0.67945 -0.305054)
			(end -0.12065 -0.305054)
			(stroke
				(width 0.1)
				(type default)
			)
			(layer "F.Fab")
		)
		(fp_line
			(start -0.67945 0.3048)
			(end -0.67945 -0.305054)
			(stroke
				(width 0.1)
				(type default)
			)
			(layer "F.Fab")
		)
		(fp_line
			(start -0.12065 -0.305054)
			(end -0.12065 -0.2794)
			(stroke
				(width 0.1)
				(type default)
			)
			(layer "F.Fab")
		)
		(fp_line
			(start -0.12065 -0.2794)
			(end 0.12065 -0.2794)
			(stroke
				(width 0.1)
				(type default)
			)
			(layer "F.Fab")
		)
		(fp_line
			(start -0.12065 0.2794)
			(end -0.12065 0.3048)
			(stroke
				(width 0.1)
				(type default)
			)
			(layer "F.Fab")
		)
		(fp_line
			(start -0.12065 0.3048)
			(end -0.67945 0.3048)
			(stroke
				(width 0.1)
				(type default)
			)
			(layer "F.Fab")
		)
		(fp_line
			(start 0.120396 0.2794)
			(end -0.12065 0.2794)
			(stroke
				(width 0.1)
				(type default)
			)
			(layer "F.Fab")
		)
		(fp_line
			(start 0.120396 0.3048)
			(end 0.120396 0.2794)
			(stroke
				(width 0.1)
				(type default)
			)
			(layer "F.Fab")
		)
		(fp_line
			(start 0.12065 -0.3048)
			(end 0.67945 -0.3048)
			(stroke
				(width 0.1)
				(type default)
			)
			(layer "F.Fab")
		)
		(fp_line
			(start 0.12065 -0.2794)
			(end 0.12065 -0.3048)
			(stroke
				(width 0.1)
				(type default)
			)
			(layer "F.Fab")
		)
		(fp_line
			(start 0.67945 -0.3048)
			(end 0.67945 0.3048)
			(stroke
				(width 0.1)
				(type default)
			)
			(layer "F.Fab")
		)
		(fp_line
			(start 0.67945 0.3048)
			(end 0.120396 0.3048)
			(stroke
				(width 0.1)
				(type default)
			)
			(layer "F.Fab")
		)
		(pad "1" smd circle
			(at -0.40005 0)
			(size 0 0)
			(layers "F.Cu" "F.Mask" "F.Paste")
			(net "P3V3_AUX")
		)
		(pad "2" smd circle
			(at 0.40005 0)
			(size 0 0)
			(layers "F.Cu" "F.Mask" "F.Paste")
			(net "FM_P2E_EQA0")
		)
	)
)
